#ISCELL
  mstr_misc dns *
  *
#ISCELL
  pure_quanta quanta_title_block_c *
  *
#ISCELL
  standard offpage *
  page171_i1
#ISCELL
  pure_quanta_power universal_gnd *
  page171_i10
#CELL
  pure_quanta q_cap *
  page171_i11
#ISCELL
  pure_quanta_power universal_gnd *
  page171_i12
#CELL
  pure_quanta q_res *
  page171_i13
#CELL
  pure_quanta q_cap *
  page171_i14
#ISCELL
  pure_quanta_power universal_gnd *
  page171_i15
#ISCELL
  pure_quanta_power vcc_core *
  page171_i16
#ISCELL
  standard offpage *
  page171_i17
#CELL
  pure_quanta isl99390frztr5935 *
  page171_i18
#ISCELL
  pure_quanta_power universal_gnd *
  page171_i19
#ISCELL
  standard offpage *
  page171_i2
#ISCELL
  pure_quanta_power universal_gnd *
  page171_i20
#CELL
  pure_quanta q_res *
  page171_i21
#CELL
  pure_quanta q_res *
  page171_i22
#CELL
  pure_quanta q_cap *
  page171_i23
#CELL
  pure_quanta q_cap *
  page171_i24
#ISCELL
  pure_quanta_power universal_gnd *
  page171_i25
#CELL
  pure_quanta q_res *
  page171_i26
#CELL
  pure_quanta q_cap *
  page171_i27
#CELL
  pure_quanta q_cap *
  page171_i28
#CELL
  pure_quanta q_cap *
  page171_i29
#ISCELL
  pure_quanta_power universal_gnd *
  page171_i3
#ISCELL
  pure_quanta_power universal_gnd *
  page171_i30
#CELL
  pure_quanta q_res *
  page171_i31
#CELL
  pure_quanta q_res *
  page171_i32
#CELL
  pure_quanta q_cap *
  page171_i33
#ISCELL
  pure_quanta_power universal_gnd *
  page171_i34
#ISCELL
  standard offpage *
  page171_i35
#CELL
  pure_quanta q_res *
  page171_i36
#ISCELL
  pure_quanta_power universal_gnd *
  page171_i37
#CELL
  pure_quanta q_cap *
  page171_i38
#ISCELL
  standard offpage *
  page171_i39
#CELL
  pure_quanta q_cap *
  page171_i4
#CELL
  pure_quanta q_res *
  page171_i40
#ISCELL
  pure_quanta_power universal_gnd *
  page171_i41
#CELL
  pure_quanta q_cap *
  page171_i42
#ISCELL
  pure_quanta_power vcc_core *
  page171_i43
#CELL
  pure_quanta q_cap *
  page171_i44
#CELL
  pure_quanta q_res *
  page171_i45
#CELL
  pure_quanta q_cap *
  page171_i46
#CELL
  pure_quanta q_cap *
  page171_i47
#CELL
  pure_quanta q_cap *
  page171_i48
#CELL
  pure_quanta q_cap *
  page171_i49
#ISCELL
  pure_quanta_power universal_gnd *
  page171_i5
#ISCELL
  pure_quanta_power universal_gnd *
  page171_i50
#CELL
  pure_quanta q_inductor *
  page171_i51
#CELL
  pure_quanta q_inductor4p_14 *
  page171_i52
#ISCELL
  pure_quanta_power universal_gnd *
  page171_i53
#CELL
  pure_quanta q_cap *
  page171_i54
#CELL
  pure_quanta q_cap *
  page171_i55
#ISCELL
  pure_quanta_power vcc_core *
  page171_i56
#ISCELL
  standard offpage *
  page171_i57
#ISCELL
  pure_quanta_power universal_gnd *
  page171_i58
#CELL
  pure_quanta q_cap *
  page171_i59
#ISCELL
  standard offpage *
  page171_i6
#CELL
  pure_quanta q_cap *
  page171_i60
#ISCELL
  pure_quanta_power vcc_core *
  page171_i61
#ISCELL
  standard offpage *
  page171_i62
#CELL
  pure_quanta q_cap *
  page171_i63
#CELL
  pure_quanta q_inductor4p_14 *
  page171_i64
#ISCELL
  pure_quanta_power universal_gnd *
  page171_i65
#CELL
  pure_quanta q_cap *
  page171_i66
#ISCELL
  pure_quanta_power vcc_core *
  page171_i67
#ISCELL
  standard offpage *
  page171_i68
#CELL
  pure_quanta q_cap *
  page171_i69
#ISCELL
  standard offpage *
  page171_i7
#ISCELL
  pure_quanta_power universal_gnd *
  page171_i70
#CELL
  pure_quanta q_cap *
  page171_i71
#ISCELL
  pure_quanta_power vcc_core *
  page171_i72
#CELL
  pure_quanta isl99390frztr5935 *
  page171_i73
#CELL
  pure_quanta q_res *
  page171_i8
#ISCELL
  standard offpage *
  page171_i9
